# BASEBOARD_FAB2 (Tioga Pass) — schematic netlist excerpt (pin names and nets, part order shuffled) for the footprints in the layout excerpt that follows; sources: Cadence DE-HDL packaged netlist, KiCad conversion of Wiwynn_Tioga_Pass_MB.brd

R3P5  RES  1.00K 1% EMPTY  pkg 0402  page 133 : A = P1V05_PCH_STBY ; B = FM_PRSNT_2_2_N
C1L18  CAP_A  1.0UF 6.3V 10% X6S  pkg 0402V  page 175 : A = FP_PWR_BTN_R1_N ; B = GND

U1M7  NC7SB3157  IC  pkg SMLF  page 112
  B1  = XDP_CPU0_TDO
  GND  = GND
  B0  = XDP_CPU1_TDO
  A  = XDP_CPU_TDO
  VCC  = P3V3_STBY
  S  = FM_CPU1_SKTOCC_LVT3_N

(kicad_pcb
	(version 20260206)
	(generator "pcbnew")
	(generator_version "10.0")
	(general
		(thickness 1.6)
		(legacy_teardrops no)
	)
	(paper "A4")
	(title_block
		(title "Wiwynn_Tioga_Pass_MB.brd")
		(comment 1 "Tioga Pass / footprints 2923-2925 of 4770")
	)
	(layers
		(0 "F.Cu" signal "TOP")
		(4 "In1.Cu" signal "L2GND")
		(6 "In2.Cu" signal "L3")
		(8 "In3.Cu" signal "L4GND")
		(10 "In4.Cu" signal "L5")
		(12 "In5.Cu" signal "L6GND")
		(14 "In6.Cu" signal "L7VCC")
		(16 "In7.Cu" signal "L8VCC")
		(18 "In8.Cu" signal "L9GND")
		(20 "In9.Cu" signal "L10")
		(22 "In10.Cu" signal "L11GND")
		(24 "In11.Cu" signal "L12")
		(26 "In12.Cu" signal "L13GND")
		(2 "B.Cu" signal "BOTTOM")
		(9 "F.Adhes" user "F.Adhesive")
		(11 "B.Adhes" user "B.Adhesive")
		(13 "F.Paste" user "Package Geometry/Pastemask Top")
		(15 "B.Paste" user "Package Geometry/Pastemask Bottom")
		(5 "F.SilkS" user "Ref Des/Silkscreen Top")
		(7 "B.SilkS" user "Ref Des/Silkscreen Bottom")
		(1 "F.Mask" user "Board Geometry/Soldermask Top")
		(3 "B.Mask" user "Board Geometry/Soldermask Bottom")
		(17 "Dwgs.User" user "User.Drawings")
		(19 "Cmts.User" user "User.Comments")
		(21 "Eco1.User" user "User.Eco1")
		(23 "Eco2.User" user "User.Eco2")
		(25 "Edge.Cuts" user "Board Geometry/Outline")
		(27 "Margin" user)
		(31 "F.CrtYd" user "Package Geometry/Place Bound Top")
		(29 "B.CrtYd" user "Package Geometry/Place Bound Bottom")
		(35 "F.Fab" user "Ref Des/Assembly Top")
		(33 "B.Fab" user "Ref Des/Assembly Bottom")
	)
	(footprint ""
		(layer "B.Cu")
		(at 469.7095 -137.795 -90)
		(property "Reference" "C1L18"
			(at 0 0 90)
			(layer "B.SilkS")
			(hide yes)
			(effects
				(font
					(size 1.27 1.27)
				)
				(justify mirror)
			)
		)
		(property "Value" ""
			(at 0 0 90)
			(layer "B.Fab")
			(effects
				(font
					(size 1.27 1.27)
				)
				(justify mirror)
			)
		)
		(duplicate_pad_numbers_are_jumpers no)
		(fp_poly
			(pts
				(xy -0.3048 -0.1016) (xy -0.3048 0.9906) (xy 0.3048 0.9906) (xy 0.3048 -0.1016)
			)
			(stroke
				(width 0)
				(type default)
			)
			(fill no)
			(layer "B.CrtYd")
		)
		(fp_line
			(start -0.3048 0.9906)
			(end -0.3048 -0.1016)
			(stroke
				(width 0.1)
				(type default)
			)
			(layer "B.Fab")
		)
		(fp_line
			(start 0.3048 0.9906)
			(end -0.3048 0.9906)
			(stroke
				(width 0.1)
				(type default)
			)
			(layer "B.Fab")
		)
		(fp_line
			(start -0.3048 -0.1016)
			(end 0.3048 -0.1016)
			(stroke
				(width 0.1)
				(type default)
			)
			(layer "B.Fab")
		)
		(fp_line
			(start 0.3048 -0.1016)
			(end 0.3048 0.9906)
			(stroke
				(width 0.1)
				(type default)
			)
			(layer "B.Fab")
		)
		(pad "1" smd rect
			(at 0 0 90)
			(size 0.508 0.508)
			(layers "B.Cu" "B.Mask" "B.Paste")
			(net "FP_PWR_BTN_R1_N")
		)
		(pad "2" smd rect
			(at 0 0.889 90)
			(size 0.508 0.508)
			(layers "B.Cu" "B.Mask" "B.Paste")
			(net "GND")
		)
		(zone
			(layer "B.Cu")
			(hatch none 0.5)
			(connect_pads
				(clearance 0)
			)
			(min_thickness 0.25)
			(keepout
				(tracks not_allowed)
				(vias allowed)
				(pads allowed)
				(copperpour not_allowed)
				(footprints allowed)
			)
			(placement
				(enabled no)
				(sheetname "")
			)
			(fill
				(thermal_gap 0.5)
				(thermal_bridge_width 0.5)
				(island_removal_mode 0)
			)
			(polygon
				(pts
					(xy 469.0745 -137.541) (xy 469.0745 -138.049) (xy 469.4555 -138.049) (xy 469.4555 -137.541)
				)
			)
		)
		(zone
			(layer "B.Cu")
			(hatch none 0.5)
			(connect_pads
				(clearance 0)
			)
			(min_thickness 0.25)
			(keepout
				(tracks allowed)
				(vias not_allowed)
				(pads allowed)
				(copperpour not_allowed)
				(footprints allowed)
			)
			(placement
				(enabled no)
				(sheetname "")
			)
			(fill
				(thermal_gap 0.5)
				(thermal_bridge_width 0.5)
				(island_removal_mode 0)
			)
			(polygon
				(pts
					(xy 469.4555 -137.541) (xy 469.4555 -138.049) (xy 469.0745 -138.049) (xy 469.0745 -137.541)
				)
			)
		)
	)
	(footprint ""
		(layer "B.Cu")
		(at 385.051808 -84.729828 180)
		(property "Reference" "R3P5"
			(at 0.8382 -0.67818 180)
			(unlocked yes)
			(layer "B.SilkS")
			(effects
				(font
					(size 0.4064 0.254)
					(thickness 0.1524)
				)
				(justify left mirror)
			)
		)
		(property "Value" ""
			(at 0 0 0)
			(layer "B.Fab")
			(effects
				(font
					(size 1.27 1.27)
				)
				(justify mirror)
			)
		)
		(duplicate_pad_numbers_are_jumpers no)
		(fp_poly
			(pts
				(xy 0.2794 -0.1016) (xy -0.2794 -0.1016) (xy -0.2794 0.9906) (xy 0.2794 0.9906)
			)
			(stroke
				(width 0)
				(type default)
			)
			(fill no)
			(layer "B.CrtYd")
		)
		(fp_line
			(start 0.2794 0.9906)
			(end -0.2794 0.9906)
			(stroke
				(width 0.1)
				(type default)
			)
			(layer "B.Fab")
		)
		(fp_line
			(start 0.2794 -0.1016)
			(end 0.2794 0.9906)
			(stroke
				(width 0.1)
				(type default)
			)
			(layer "B.Fab")
		)
		(fp_line
			(start -0.2794 0.9906)
			(end -0.2794 -0.1016)
			(stroke
				(width 0.1)
				(type default)
			)
			(layer "B.Fab")
		)
		(fp_line
			(start -0.2794 -0.1016)
			(end 0.2794 -0.1016)
			(stroke
				(width 0.1)
				(type default)
			)
			(layer "B.Fab")
		)
		(pad "1" smd rect
			(at 0 0)
			(size 0.508 0.508)
			(layers "B.Cu" "B.Mask" "B.Paste")
			(net "P1V05_PCH_STBY")
		)
		(pad "2" smd rect
			(at 0 0.889)
			(size 0.508 0.508)
			(layers "B.Cu" "B.Mask" "B.Paste")
			(net "FM_PRSNT_2_2_N")
		)
		(zone
			(layer "B.Cu")
			(hatch none 0.5)
			(connect_pads
				(clearance 0)
			)
			(min_thickness 0.25)
			(keepout
				(tracks not_allowed)
				(vias allowed)
				(pads allowed)
				(copperpour not_allowed)
				(footprints allowed)
			)
			(placement
				(enabled no)
				(sheetname "")
			)
			(fill
				(thermal_gap 0.5)
				(thermal_bridge_width 0.5)
				(island_removal_mode 0)
			)
			(polygon
				(pts
					(xy 384.797808 -85.364828) (xy 385.305808 -85.364828) (xy 385.305808 -84.983828) (xy 384.797808 -84.983828)
				)
			)
		)
		(zone
			(layer "B.Cu")
			(hatch none 0.5)
			(connect_pads
				(clearance 0)
			)
			(min_thickness 0.25)
			(keepout
				(tracks allowed)
				(vias not_allowed)
				(pads allowed)
				(copperpour not_allowed)
				(footprints allowed)
			)
			(placement
				(enabled no)
				(sheetname "")
			)
			(fill
				(thermal_gap 0.5)
				(thermal_bridge_width 0.5)
				(island_removal_mode 0)
			)
			(polygon
				(pts
					(xy 384.797808 -84.983828) (xy 385.305808 -84.983828) (xy 385.305808 -85.364828) (xy 384.797808 -85.364828)
				)
			)
		)
	)
	(footprint ""
		(layer "B.Cu")
		(at 459.0034 -127.9144 -90)
		(property "Reference" "U1M7"
			(at 1.40843 -0.70866 0)
			(unlocked yes)
			(layer "B.SilkS")
			(effects
				(font
					(size 0.7874 0.5842)
					(thickness 0.1524)
				)
				(justify left mirror)
			)
		)
		(property "Value" ""
			(at 0 0 90)
			(layer "B.Fab")
			(effects
				(font
					(size 1.27 1.27)
				)
				(justify mirror)
			)
		)
		(duplicate_pad_numbers_are_jumpers no)
		(fp_circle
			(center 0.858266 0.002032)
			(end 0.858266 -0.124968)
			(stroke
				(width 0.254)
				(type default)
			)
			(fill no)
			(layer "B.SilkS")
		)
		(fp_poly
			(pts
				(xy -0.21463 -0.450088) (xy -1.56337 -0.450088) (xy -1.56337 1.75006) (xy -0.21463 1.75006)
			)
			(stroke
				(width 0)
				(type default)
			)
			(fill no)
			(layer "B.CrtYd")
		)
		(fp_line
			(start -1.56337 1.75006)
			(end -0.21463 1.75006)
			(stroke
				(width 0.1)
				(type default)
			)
			(layer "B.Fab")
		)
		(fp_line
			(start -0.21463 1.75006)
			(end -0.21463 -0.450088)
			(stroke
				(width 0.1)
				(type default)
			)
			(layer "B.Fab")
		)
		(fp_line
			(start -1.56337 -0.450088)
			(end -1.56337 1.75006)
			(stroke
				(width 0.1)
				(type default)
			)
			(layer "B.Fab")
		)
		(fp_line
			(start -0.21463 -0.450088)
			(end -1.56337 -0.450088)
			(stroke
				(width 0.1)
				(type default)
			)
			(layer "B.Fab")
		)
		(fp_circle
			(center 0.848614 -0.6477)
			(end 0.848614 -0.7747)
			(stroke
				(width 0.254)
				(type default)
			)
			(fill no)
			(layer "B.Fab")
		)
		(pad "1" smd rect
			(at 0 0 90)
			(size 1.016 0.381)
			(layers "B.Cu" "B.Mask" "B.Paste")
			(net "XDP_CPU0_TDO")
		)
		(pad "2" smd rect
			(at 0 0.649986 90)
			(size 1.016 0.381)
			(layers "B.Cu" "B.Mask" "B.Paste")
			(net "GND")
		)
		(pad "3" smd rect
			(at 0 1.299972 90)
			(size 1.016 0.381)
			(layers "B.Cu" "B.Mask" "B.Paste")
			(net "XDP_CPU1_TDO")
		)
		(pad "4" smd rect
			(at -1.778 1.299972 90)
			(size 1.016 0.381)
			(layers "B.Cu" "B.Mask" "B.Paste")
			(net "XDP_CPU_TDO")
		)
		(pad "5" smd rect
			(at -1.778 0.649986 90)
			(size 1.016 0.381)
			(layers "B.Cu" "B.Mask" "B.Paste")
			(net "P3V3_STBY")
		)
		(pad "6" smd rect
			(at -1.778 0 90)
			(size 1.016 0.381)
			(layers "B.Cu" "B.Mask" "B.Paste")
			(net "FM_CPU1_SKTOCC_LVT3_N")
		)
	)
)
